# T6G (Grand Teton) — schematic netlist excerpt (pin names and nets, part order shuffled) for the footprints in the layout excerpt that follows; sources: Cadence DE-HDL packaged netlist, KiCad conversion of 04192023_DAF0TMB3IC0_F0TG_MB_C_brd_V02_OCP.brd

H75  HOLE  EMPTY  pkg TH  page 230 : \1\ = NC
C765  Q_CAP_DIFFBUS  DIFF BUS_0.22UF 6.3V 20% X6S  pkg C0201  page 66 : \1\ = P5E_CPU1_P2_TX_C_DP<4> ; \2\ = P5E_CPU1_P2_TX_DP<4>
R788  Q_RES  4.7K 5% EMPTY  pkg 0201LF  page 331 : A = P1V8_CPU1_RT_1D ; B = TEST2_RT_CPU1_P1
R8119  Q_RES  1K 1% CHIP  pkg 0402LF  page 268 : A = P3V3_AUX ; B = FM_UV_ADR_TRIGGER_N

(kicad_pcb
	(version 20260206)
	(generator "pcbnew")
	(generator_version "10.0")
	(general
		(thickness 1.6)
		(legacy_teardrops no)
	)
	(paper "A4")
	(title_block
		(title "04192023_DAF0TMB3IC0_F0TG_MB_C_brd_V02_OCP.brd")
		(comment 1 "Grand Teton / footprints 3079-3082 of 8354")
	)
	(layers
		(0 "F.Cu" signal "TOP")
		(4 "In1.Cu" signal "GND")
		(6 "In2.Cu" signal "IN1")
		(8 "In3.Cu" signal "GND1")
		(10 "In4.Cu" signal "IN2")
		(12 "In5.Cu" signal "GND2")
		(14 "In6.Cu" signal "IN3")
		(16 "In7.Cu" signal "GND3")
		(18 "In8.Cu" signal "VCC")
		(20 "In9.Cu" signal "VCC1")
		(22 "In10.Cu" signal "GND4")
		(24 "In11.Cu" signal "IN4")
		(26 "In12.Cu" signal "GND5")
		(28 "In13.Cu" signal "IN5")
		(30 "In14.Cu" signal "GND6")
		(32 "In15.Cu" signal "IN6")
		(34 "In16.Cu" signal "GND7")
		(2 "B.Cu" signal "BOTTOM")
		(9 "F.Adhes" user "F.Adhesive")
		(11 "B.Adhes" user "B.Adhesive")
		(13 "F.Paste" user "Package Geometry/Pastemask Top")
		(15 "B.Paste" user "Package Geometry/Pastemask Bottom")
		(5 "F.SilkS" user "Ref Des/Silkscreen Top")
		(7 "B.SilkS" user "Ref Des/Silkscreen Bottom")
		(1 "F.Mask" user "Board Geometry/Soldermask Top")
		(3 "B.Mask" user "Board Geometry/Soldermask Bottom")
		(17 "Dwgs.User" user "User.Drawings")
		(19 "Cmts.User" user "User.Comments")
		(21 "Eco1.User" user "User.Eco1")
		(23 "Eco2.User" user "User.Eco2")
		(25 "Edge.Cuts" user "Board Geometry/Outline")
		(27 "Margin" user)
		(31 "F.CrtYd" user "Package Geometry/Place Bound Top")
		(29 "B.CrtYd" user "Package Geometry/Place Bound Bottom")
		(35 "F.Fab" user "Ref Des/Assembly Top")
		(33 "B.Fab" user "Ref Des/Assembly Bottom")
	)
	(footprint ""
		(layer "F.Cu")
		(at 93.582998 -47.049944 90)
		(property "Reference" "H75"
			(at -3.856482 -4.516374 0)
			(unlocked yes)
			(layer "F.SilkS")
			(effects
				(font
					(size 0.7874 0.5842)
					(thickness 0.1524)
				)
			)
		)
		(property "Value" ""
			(at 0 0 90)
			(layer "F.Fab")
			(effects
				(font
					(size 1.27 1.27)
				)
			)
		)
		(duplicate_pad_numbers_are_jumpers no)
		(pad "" np_thru_hole circle
			(at 0 0 90)
			(size 0 0)
			(drill oval 3.2004 4.8006)
			(layers "*.Cu" "*.Mask")
			(clearance -1.2192)
			(thermal_gap 0.381)
			(padstack
				(mode front_inner_back)
				(layer "Inner"
					(shape oval)
					(size 3.2004 4.8006)
					(clearance 0.381)
				)
				(layer "B.Cu"
					(shape circle)
					(size 0 0)
					(clearance -1.2192)
				)
			)
		)
		(zone
			(layers "F.Cu" "B.Cu" "In1.Cu" "In2.Cu" "In3.Cu" "In4.Cu" "In5.Cu" "In6.Cu"
				"In7.Cu" "In8.Cu" "In9.Cu" "In10.Cu" "In11.Cu" "In12.Cu" "In13.Cu" "In14.Cu"
				"In15.Cu" "In16.Cu"
			)
			(hatch none 0.5)
			(connect_pads
				(clearance 0)
			)
			(min_thickness 0.25)
			(keepout
				(tracks not_allowed)
				(vias allowed)
				(pads allowed)
				(copperpour not_allowed)
				(footprints allowed)
			)
			(placement
				(enabled no)
				(sheetname "")
			)
			(fill
				(thermal_gap 0.5)
				(thermal_bridge_width 0.5)
				(island_removal_mode 0)
			)
			(polygon
				(pts
					(arc
						(start 94.383098 -49.158144)
						(mid 96.491298 -47.049944)
						(end 94.383098 -44.941744)
					)
					(arc
						(start 92.782898 -44.941744)
						(mid 90.674698 -47.049944)
						(end 92.782898 -49.158144)
					)
				)
			)
		)
		(zone
			(layers "F.Cu" "B.Cu" "In1.Cu" "In2.Cu" "In3.Cu" "In4.Cu" "In5.Cu" "In6.Cu"
				"In7.Cu" "In8.Cu" "In9.Cu" "In10.Cu" "In11.Cu" "In12.Cu" "In13.Cu" "In14.Cu"
				"In15.Cu" "In16.Cu"
			)
			(hatch none 0.5)
			(connect_pads
				(clearance 0)
			)
			(min_thickness 0.25)
			(keepout
				(tracks not_allowed)
				(vias allowed)
				(pads allowed)
				(copperpour not_allowed)
				(footprints allowed)
			)
			(placement
				(enabled no)
				(sheetname "")
			)
			(fill
				(thermal_gap 0.5)
				(thermal_bridge_width 0.5)
				(island_removal_mode 0)
			)
			(polygon
				(pts
					(arc
						(start 94.383098 -50.050192)
						(mid 97.383346 -47.049944)
						(end 94.383098 -44.049696)
					)
					(arc
						(start 92.782898 -44.049696)
						(mid 89.78265 -47.049944)
						(end 92.782898 -50.050192)
					)
				)
			)
		)
	)
	(footprint ""
		(layer "F.Cu")
		(at 147.722844 -375.49963 -90)
		(property "Reference" "C765"
			(at 0 0 270)
			(layer "F.SilkS")
			(hide yes)
			(effects
				(font
					(size 1.27 1.27)
				)
			)
		)
		(property "Value" ""
			(at 0 0 270)
			(layer "F.Fab")
			(effects
				(font
					(size 1.27 1.27)
				)
			)
		)
		(duplicate_pad_numbers_are_jumpers no)
		(fp_line
			(start -0.299974 0.150114)
			(end -0.299974 -0.150114)
			(stroke
				(width 0.1)
				(type default)
			)
			(layer "F.Fab")
		)
		(fp_line
			(start 0.299974 0.150114)
			(end -0.299974 0.150114)
			(stroke
				(width 0.1)
				(type default)
			)
			(layer "F.Fab")
		)
		(fp_line
			(start -0.299974 -0.150114)
			(end 0.299974 -0.150114)
			(stroke
				(width 0.1)
				(type default)
			)
			(layer "F.Fab")
		)
		(fp_line
			(start 0.299974 -0.150114)
			(end 0.299974 0.150114)
			(stroke
				(width 0.1)
				(type default)
			)
			(layer "F.Fab")
		)
		(pad "1" smd rect
			(at -0.2667 0 270)
			(size 0.3048 0.381)
			(layers "F.Cu" "F.Mask" "F.Paste")
			(net "P5E_CPU1_P2_TX_C_DP<4>")
		)
		(pad "2" smd rect
			(at 0.2667 0 270)
			(size 0.3048 0.381)
			(layers "F.Cu" "F.Mask" "F.Paste")
			(net "P5E_CPU1_P2_TX_DP<4>")
		)
	)
	(footprint ""
		(layer "F.Cu")
		(at 150.420324 -115.377468)
		(property "Reference" "R8119"
			(at 0 0 0)
			(layer "F.SilkS")
			(hide yes)
			(effects
				(font
					(size 1.27 1.27)
				)
			)
		)
		(property "Value" ""
			(at 0 0 0)
			(layer "F.Fab")
			(effects
				(font
					(size 1.27 1.27)
				)
			)
		)
		(duplicate_pad_numbers_are_jumpers no)
		(fp_line
			(start -0.7874 -0.4064)
			(end 0.7874 -0.4064)
			(stroke
				(width 0.1524)
				(type default)
			)
			(layer "F.SilkS")
		)
		(fp_line
			(start -0.7874 0.4064)
			(end -0.7874 -0.4064)
			(stroke
				(width 0.1524)
				(type default)
			)
			(layer "F.SilkS")
		)
		(fp_line
			(start 0.7874 -0.4064)
			(end 0.7874 0.4064)
			(stroke
				(width 0.1524)
				(type default)
			)
			(layer "F.SilkS")
		)
		(fp_line
			(start 0.7874 0.4064)
			(end -0.7874 0.4064)
			(stroke
				(width 0.1524)
				(type default)
			)
			(layer "F.SilkS")
		)
		(fp_line
			(start -0.67945 -0.305054)
			(end -0.12065 -0.305054)
			(stroke
				(width 0.1)
				(type default)
			)
			(layer "F.Fab")
		)
		(fp_line
			(start -0.67945 0.3048)
			(end -0.67945 -0.305054)
			(stroke
				(width 0.1)
				(type default)
			)
			(layer "F.Fab")
		)
		(fp_line
			(start -0.12065 -0.305054)
			(end -0.12065 -0.2794)
			(stroke
				(width 0.1)
				(type default)
			)
			(layer "F.Fab")
		)
		(fp_line
			(start -0.12065 -0.2794)
			(end 0.12065 -0.2794)
			(stroke
				(width 0.1)
				(type default)
			)
			(layer "F.Fab")
		)
		(fp_line
			(start -0.12065 0.2794)
			(end -0.12065 0.3048)
			(stroke
				(width 0.1)
				(type default)
			)
			(layer "F.Fab")
		)
		(fp_line
			(start -0.12065 0.3048)
			(end -0.67945 0.3048)
			(stroke
				(width 0.1)
				(type default)
			)
			(layer "F.Fab")
		)
		(fp_line
			(start 0.120396 0.2794)
			(end -0.12065 0.2794)
			(stroke
				(width 0.1)
				(type default)
			)
			(layer "F.Fab")
		)
		(fp_line
			(start 0.120396 0.3048)
			(end 0.120396 0.2794)
			(stroke
				(width 0.1)
				(type default)
			)
			(layer "F.Fab")
		)
		(fp_line
			(start 0.12065 -0.3048)
			(end 0.67945 -0.3048)
			(stroke
				(width 0.1)
				(type default)
			)
			(layer "F.Fab")
		)
		(fp_line
			(start 0.12065 -0.2794)
			(end 0.12065 -0.3048)
			(stroke
				(width 0.1)
				(type default)
			)
			(layer "F.Fab")
		)
		(fp_line
			(start 0.67945 -0.3048)
			(end 0.67945 0.3048)
			(stroke
				(width 0.1)
				(type default)
			)
			(layer "F.Fab")
		)
		(fp_line
			(start 0.67945 0.3048)
			(end 0.120396 0.3048)
			(stroke
				(width 0.1)
				(type default)
			)
			(layer "F.Fab")
		)
		(pad "1" smd circle
			(at -0.40005 0)
			(size 0 0)
			(layers "F.Cu" "F.Mask" "F.Paste")
			(net "P3V3_AUX")
		)
		(pad "2" smd circle
			(at 0.40005 0)
			(size 0 0)
			(layers "F.Cu" "F.Mask" "F.Paste")
			(net "FM_UV_ADR_TRIGGER_N")
		)
	)
	(footprint ""
		(layer "F.Cu")
		(at 74.2696 -383.7432)
		(property "Reference" "R788"
			(at 0 0 0)
			(layer "F.SilkS")
			(hide yes)
			(effects
				(font
					(size 1.27 1.27)
				)
			)
		)
		(property "Value" ""
			(at 0 0 0)
			(layer "F.Fab")
			(effects
				(font
					(size 1.27 1.27)
				)
			)
		)
		(duplicate_pad_numbers_are_jumpers no)
		(fp_line
			(start -0.32512 -0.175006)
			(end 0.32512 -0.175006)
			(stroke
				(width 0.1)
				(type default)
			)
			(layer "F.Fab")
		)
		(fp_line
			(start -0.32512 0.175006)
			(end -0.32512 -0.175006)
			(stroke
				(width 0.1)
				(type default)
			)
			(layer "F.Fab")
		)
		(fp_line
			(start 0.32512 -0.175006)
			(end 0.32512 0.175006)
			(stroke
				(width 0.1)
				(type default)
			)
			(layer "F.Fab")
		)
		(fp_line
			(start 0.32512 0.175006)
			(end -0.32512 0.175006)
			(stroke
				(width 0.1)
				(type default)
			)
			(layer "F.Fab")
		)
		(pad "1" smd rect
			(at -0.2667 0)
			(size 0.3048 0.381)
			(layers "F.Cu" "F.Mask" "F.Paste")
			(net "P1V8_CPU1_RT_1D")
		)
		(pad "2" smd rect
			(at 0.2667 0 180)
			(size 0.3048 0.381)
			(layers "F.Cu" "F.Mask" "F.Paste")
			(net "TEST2_RT_CPU1_P1")
		)
	)
)
